(kicad_pcb
	(version 20260206)
	(generator "pcbnew")
	(generator_version "10.0")
	(general
		(thickness 1.6)
		(legacy_teardrops no)
	)
	(paper "A4")
	(title_block
		(title "01162023_DA0F0TEBIF0_F0T_Expander_BD_F_brd_V02_OCP.brd")
		(comment 1 "Grand Teton / footprints 5817-5823 of 9728")
	)
	(layers
		(0 "F.Cu" signal "TOP")
		(4 "In1.Cu" signal "GND")
		(6 "In2.Cu" signal "VCC")
		(8 "In3.Cu" signal "VCC1")
		(10 "In4.Cu" signal "GND1")
		(12 "In5.Cu" signal "IN1")
		(14 "In6.Cu" signal "GND2")
		(16 "In7.Cu" signal "IN2")
		(18 "In8.Cu" signal "GND3")
		(20 "In9.Cu" signal "IN3")
		(22 "In10.Cu" signal "GND4")
		(24 "In11.Cu" signal "IN4")
		(26 "In12.Cu" signal "GND5")
		(28 "In13.Cu" signal "IN5")
		(30 "In14.Cu" signal "GND6")
		(32 "In15.Cu" signal "IN6")
		(34 "In16.Cu" signal "GND7")
		(2 "B.Cu" signal "BOTTOM")
		(9 "F.Adhes" user "F.Adhesive")
		(11 "B.Adhes" user "B.Adhesive")
		(13 "F.Paste" user "Package Geometry/Pastemask Top")
		(15 "B.Paste" user "Package Geometry/Pastemask Bottom")
		(5 "F.SilkS" user "Ref Des/Silkscreen Top")
		(7 "B.SilkS" user "Ref Des/Silkscreen Bottom")
		(1 "F.Mask" user "Board Geometry/Soldermask Top")
		(3 "B.Mask" user "Board Geometry/Soldermask Bottom")
		(17 "Dwgs.User" user "User.Drawings")
		(19 "Cmts.User" user "User.Comments")
		(21 "Eco1.User" user "User.Eco1")
		(23 "Eco2.User" user "User.Eco2")
		(25 "Edge.Cuts" user "Board Geometry/Outline")
		(27 "Margin" user)
		(31 "F.CrtYd" user "Package Geometry/Place Bound Top")
		(29 "B.CrtYd" user "Package Geometry/Place Bound Bottom")
		(35 "F.Fab" user "Ref Des/Assembly Top")
		(33 "B.Fab" user "Ref Des/Assembly Bottom")
	)
	(footprint ""
		(layer "F.Cu")
		(at 217.235786 -226.811586 180)
		(property "Reference" "R1481"
			(at 0 0 180)
			(layer "F.SilkS")
			(hide yes)
			(effects
				(font
					(size 1.27 1.27)
				)
			)
		)
		(property "Value" ""
			(at 0 0 180)
			(layer "F.Fab")
			(effects
				(font
					(size 1.27 1.27)
				)
			)
		)
		(duplicate_pad_numbers_are_jumpers no)
		(fp_line
			(start 0.7874 0.4064)
			(end -0.7874 0.4064)
			(stroke
				(width 0.1524)
				(type default)
			)
			(layer "F.SilkS")
		)
		(fp_line
			(start 0.7874 -0.4064)
			(end 0.7874 0.4064)
			(stroke
				(width 0.1524)
				(type default)
			)
			(layer "F.SilkS")
		)
		(fp_line
			(start -0.7874 0.4064)
			(end -0.7874 -0.4064)
			(stroke
				(width 0.1524)
				(type default)
			)
			(layer "F.SilkS")
		)
		(fp_line
			(start -0.7874 -0.4064)
			(end 0.7874 -0.4064)
			(stroke
				(width 0.1524)
				(type default)
			)
			(layer "F.SilkS")
		)
		(fp_line
			(start 0.67945 0.3048)
			(end 0.120396 0.3048)
			(stroke
				(width 0.1)
				(type default)
			)
			(layer "F.Fab")
		)
		(fp_line
			(start 0.67945 -0.3048)
			(end 0.67945 0.3048)
			(stroke
				(width 0.1)
				(type default)
			)
			(layer "F.Fab")
		)
		(fp_line
			(start 0.12065 -0.2794)
			(end 0.12065 -0.3048)
			(stroke
				(width 0.1)
				(type default)
			)
			(layer "F.Fab")
		)
		(fp_line
			(start 0.12065 -0.3048)
			(end 0.67945 -0.3048)
			(stroke
				(width 0.1)
				(type default)
			)
			(layer "F.Fab")
		)
		(fp_line
			(start 0.120396 0.3048)
			(end 0.120396 0.2794)
			(stroke
				(width 0.1)
				(type default)
			)
			(layer "F.Fab")
		)
		(fp_line
			(start 0.120396 0.2794)
			(end -0.12065 0.2794)
			(stroke
				(width 0.1)
				(type default)
			)
			(layer "F.Fab")
		)
		(fp_line
			(start -0.12065 0.3048)
			(end -0.67945 0.3048)
			(stroke
				(width 0.1)
				(type default)
			)
			(layer "F.Fab")
		)
		(fp_line
			(start -0.12065 0.2794)
			(end -0.12065 0.3048)
			(stroke
				(width 0.1)
				(type default)
			)
			(layer "F.Fab")
		)
		(fp_line
			(start -0.12065 -0.2794)
			(end 0.12065 -0.2794)
			(stroke
				(width 0.1)
				(type default)
			)
			(layer "F.Fab")
		)
		(fp_line
			(start -0.12065 -0.305054)
			(end -0.12065 -0.2794)
			(stroke
				(width 0.1)
				(type default)
			)
			(layer "F.Fab")
		)
		(fp_line
			(start -0.67945 0.3048)
			(end -0.67945 -0.305054)
			(stroke
				(width 0.1)
				(type default)
			)
			(layer "F.Fab")
		)
		(fp_line
			(start -0.67945 -0.305054)
			(end -0.12065 -0.305054)
			(stroke
				(width 0.1)
				(type default)
			)
			(layer "F.Fab")
		)
		(pad "1" smd circle
			(at -0.40005 0 180)
			(size 0 0)
			(layers "F.Cu" "F.Mask" "F.Paste")
			(net "SMB_NIC2_SCL")
		)
		(pad "2" smd circle
			(at 0.40005 0 180)
			(size 0 0)
			(layers "F.Cu" "F.Mask" "F.Paste")
			(net "SMB_NIC2_R_SCL")
		)
	)
	(footprint ""
		(layer "F.Cu")
		(at 126.210314 -124.963428 180)
		(property "Reference" "R4478"
			(at 0 0 180)
			(layer "F.SilkS")
			(hide yes)
			(effects
				(font
					(size 1.27 1.27)
				)
			)
		)
		(property "Value" ""
			(at 0 0 180)
			(layer "F.Fab")
			(effects
				(font
					(size 1.27 1.27)
				)
			)
		)
		(duplicate_pad_numbers_are_jumpers no)
		(fp_line
			(start 0.7874 0.4064)
			(end -0.7874 0.4064)
			(stroke
				(width 0.1524)
				(type default)
			)
			(layer "F.SilkS")
		)
		(fp_line
			(start 0.7874 -0.4064)
			(end 0.7874 0.4064)
			(stroke
				(width 0.1524)
				(type default)
			)
			(layer "F.SilkS")
		)
		(fp_line
			(start -0.7874 0.4064)
			(end -0.7874 -0.4064)
			(stroke
				(width 0.1524)
				(type default)
			)
			(layer "F.SilkS")
		)
		(fp_line
			(start -0.7874 -0.4064)
			(end 0.7874 -0.4064)
			(stroke
				(width 0.1524)
				(type default)
			)
			(layer "F.SilkS")
		)
		(fp_line
			(start 0.67945 0.3048)
			(end 0.120396 0.3048)
			(stroke
				(width 0.1)
				(type default)
			)
			(layer "F.Fab")
		)
		(fp_line
			(start 0.67945 -0.3048)
			(end 0.67945 0.3048)
			(stroke
				(width 0.1)
				(type default)
			)
			(layer "F.Fab")
		)
		(fp_line
			(start 0.12065 -0.2794)
			(end 0.12065 -0.3048)
			(stroke
				(width 0.1)
				(type default)
			)
			(layer "F.Fab")
		)
		(fp_line
			(start 0.12065 -0.3048)
			(end 0.67945 -0.3048)
			(stroke
				(width 0.1)
				(type default)
			)
			(layer "F.Fab")
		)
		(fp_line
			(start 0.120396 0.3048)
			(end 0.120396 0.2794)
			(stroke
				(width 0.1)
				(type default)
			)
			(layer "F.Fab")
		)
		(fp_line
			(start 0.120396 0.2794)
			(end -0.12065 0.2794)
			(stroke
				(width 0.1)
				(type default)
			)
			(layer "F.Fab")
		)
		(fp_line
			(start -0.12065 0.3048)
			(end -0.67945 0.3048)
			(stroke
				(width 0.1)
				(type default)
			)
			(layer "F.Fab")
		)
		(fp_line
			(start -0.12065 0.2794)
			(end -0.12065 0.3048)
			(stroke
				(width 0.1)
				(type default)
			)
			(layer "F.Fab")
		)
		(fp_line
			(start -0.12065 -0.2794)
			(end 0.12065 -0.2794)
			(stroke
				(width 0.1)
				(type default)
			)
			(layer "F.Fab")
		)
		(fp_line
			(start -0.12065 -0.305054)
			(end -0.12065 -0.2794)
			(stroke
				(width 0.1)
				(type default)
			)
			(layer "F.Fab")
		)
		(fp_line
			(start -0.67945 0.3048)
			(end -0.67945 -0.305054)
			(stroke
				(width 0.1)
				(type default)
			)
			(layer "F.Fab")
		)
		(fp_line
			(start -0.67945 -0.305054)
			(end -0.12065 -0.305054)
			(stroke
				(width 0.1)
				(type default)
			)
			(layer "F.Fab")
		)
		(pad "1" smd circle
			(at -0.40005 0 180)
			(size 0 0)
			(layers "F.Cu" "F.Mask" "F.Paste")
			(net "PWRGD_P3V3_NIC2")
		)
		(pad "2" smd circle
			(at 0.40005 0 180)
			(size 0 0)
			(layers "F.Cu" "F.Mask" "F.Paste")
			(net "PWRGD_P3V3_NIC2_R")
		)
	)
	(footprint ""
		(layer "F.Cu")
		(at 225.31705 -305.375564)
		(property "Reference" "PC230"
			(at 0 0 0)
			(layer "F.SilkS")
			(hide yes)
			(effects
				(font
					(size 1.27 1.27)
				)
			)
		)
		(property "Value" ""
			(at 0 0 0)
			(layer "F.Fab")
			(effects
				(font
					(size 1.27 1.27)
				)
			)
		)
		(duplicate_pad_numbers_are_jumpers no)
		(fp_line
			(start -0.7874 -0.4064)
			(end 0.7874 -0.4064)
			(stroke
				(width 0.1524)
				(type default)
			)
			(layer "F.SilkS")
		)
		(fp_line
			(start -0.7874 0.4064)
			(end -0.7874 -0.4064)
			(stroke
				(width 0.1524)
				(type default)
			)
			(layer "F.SilkS")
		)
		(fp_line
			(start 0.7874 -0.4064)
			(end 0.7874 0.4064)
			(stroke
				(width 0.1524)
				(type default)
			)
			(layer "F.SilkS")
		)
		(fp_line
			(start 0.7874 0.4064)
			(end -0.7874 0.4064)
			(stroke
				(width 0.1524)
				(type default)
			)
			(layer "F.SilkS")
		)
		(fp_line
			(start -0.67945 -0.305054)
			(end -0.12065 -0.305054)
			(stroke
				(width 0.1)
				(type default)
			)
			(layer "F.Fab")
		)
		(fp_line
			(start -0.67945 0.3048)
			(end -0.67945 -0.305054)
			(stroke
				(width 0.1)
				(type default)
			)
			(layer "F.Fab")
		)
		(fp_line
			(start -0.12065 -0.305054)
			(end -0.12065 -0.2794)
			(stroke
				(width 0.1)
				(type default)
			)
			(layer "F.Fab")
		)
		(fp_line
			(start -0.12065 -0.2794)
			(end 0.12065 -0.2794)
			(stroke
				(width 0.1)
				(type default)
			)
			(layer "F.Fab")
		)
		(fp_line
			(start -0.12065 0.2794)
			(end -0.12065 0.3048)
			(stroke
				(width 0.1)
				(type default)
			)
			(layer "F.Fab")
		)
		(fp_line
			(start -0.12065 0.3048)
			(end -0.67945 0.3048)
			(stroke
				(width 0.1)
				(type default)
			)
			(layer "F.Fab")
		)
		(fp_line
			(start 0.120396 0.2794)
			(end -0.12065 0.2794)
			(stroke
				(width 0.1)
				(type default)
			)
			(layer "F.Fab")
		)
		(fp_line
			(start 0.120396 0.3048)
			(end 0.120396 0.2794)
			(stroke
				(width 0.1)
				(type default)
			)
			(layer "F.Fab")
		)
		(fp_line
			(start 0.12065 -0.3048)
			(end 0.67945 -0.3048)
			(stroke
				(width 0.1)
				(type default)
			)
			(layer "F.Fab")
		)
		(fp_line
			(start 0.12065 -0.2794)
			(end 0.12065 -0.3048)
			(stroke
				(width 0.1)
				(type default)
			)
			(layer "F.Fab")
		)
		(fp_line
			(start 0.67945 -0.3048)
			(end 0.67945 0.3048)
			(stroke
				(width 0.1)
				(type default)
			)
			(layer "F.Fab")
		)
		(fp_line
			(start 0.67945 0.3048)
			(end 0.120396 0.3048)
			(stroke
				(width 0.1)
				(type default)
			)
			(layer "F.Fab")
		)
		(pad "1" smd circle
			(at -0.40005 0)
			(size 0 0)
			(layers "F.Cu" "F.Mask" "F.Paste")
			(net "SW_P12V_P1V25_PEX1_FLT")
		)
		(pad "2" smd circle
			(at 0.40005 0)
			(size 0 0)
			(layers "F.Cu" "F.Mask" "F.Paste")
			(net "GND")
		)
	)
	(footprint ""
		(layer "F.Cu")
		(at 350.380554 -90.645234)
		(property "Reference" "R1598"
			(at 0 0 0)
			(layer "F.SilkS")
			(hide yes)
			(effects
				(font
					(size 1.27 1.27)
				)
			)
		)
		(property "Value" ""
			(at 0 0 0)
			(layer "F.Fab")
			(effects
				(font
					(size 1.27 1.27)
				)
			)
		)
		(duplicate_pad_numbers_are_jumpers no)
		(fp_line
			(start -0.7874 -0.4064)
			(end 0.7874 -0.4064)
			(stroke
				(width 0.1524)
				(type default)
			)
			(layer "F.SilkS")
		)
		(fp_line
			(start -0.7874 0.4064)
			(end -0.7874 -0.4064)
			(stroke
				(width 0.1524)
				(type default)
			)
			(layer "F.SilkS")
		)
		(fp_line
			(start 0.7874 -0.4064)
			(end 0.7874 0.4064)
			(stroke
				(width 0.1524)
				(type default)
			)
			(layer "F.SilkS")
		)
		(fp_line
			(start 0.7874 0.4064)
			(end -0.7874 0.4064)
			(stroke
				(width 0.1524)
				(type default)
			)
			(layer "F.SilkS")
		)
		(fp_line
			(start -0.67945 -0.305054)
			(end -0.12065 -0.305054)
			(stroke
				(width 0.1)
				(type default)
			)
			(layer "F.Fab")
		)
		(fp_line
			(start -0.67945 0.3048)
			(end -0.67945 -0.305054)
			(stroke
				(width 0.1)
				(type default)
			)
			(layer "F.Fab")
		)
		(fp_line
			(start -0.12065 -0.305054)
			(end -0.12065 -0.2794)
			(stroke
				(width 0.1)
				(type default)
			)
			(layer "F.Fab")
		)
		(fp_line
			(start -0.12065 -0.2794)
			(end 0.12065 -0.2794)
			(stroke
				(width 0.1)
				(type default)
			)
			(layer "F.Fab")
		)
		(fp_line
			(start -0.12065 0.2794)
			(end -0.12065 0.3048)
			(stroke
				(width 0.1)
				(type default)
			)
			(layer "F.Fab")
		)
		(fp_line
			(start -0.12065 0.3048)
			(end -0.67945 0.3048)
			(stroke
				(width 0.1)
				(type default)
			)
			(layer "F.Fab")
		)
		(fp_line
			(start 0.120396 0.2794)
			(end -0.12065 0.2794)
			(stroke
				(width 0.1)
				(type default)
			)
			(layer "F.Fab")
		)
		(fp_line
			(start 0.120396 0.3048)
			(end 0.120396 0.2794)
			(stroke
				(width 0.1)
				(type default)
			)
			(layer "F.Fab")
		)
		(fp_line
			(start 0.12065 -0.3048)
			(end 0.67945 -0.3048)
			(stroke
				(width 0.1)
				(type default)
			)
			(layer "F.Fab")
		)
		(fp_line
			(start 0.12065 -0.2794)
			(end 0.12065 -0.3048)
			(stroke
				(width 0.1)
				(type default)
			)
			(layer "F.Fab")
		)
		(fp_line
			(start 0.67945 -0.3048)
			(end 0.67945 0.3048)
			(stroke
				(width 0.1)
				(type default)
			)
			(layer "F.Fab")
		)
		(fp_line
			(start 0.67945 0.3048)
			(end 0.120396 0.3048)
			(stroke
				(width 0.1)
				(type default)
			)
			(layer "F.Fab")
		)
		(pad "1" smd circle
			(at -0.40005 0)
			(size 0 0)
			(layers "F.Cu" "F.Mask" "F.Paste")
			(net "P3V3_AUX")
		)
		(pad "2" smd circle
			(at 0.40005 0)
			(size 0 0)
			(layers "F.Cu" "F.Mask" "F.Paste")
			(net "BIC_I2C9_SSD_MUX1_A1")
		)
	)
	(footprint ""
		(layer "F.Cu")
		(at 336.586068 -272.15846 -90)
		(property "Reference" "PL11"
			(at 1.04013 -2.958338 90)
			(unlocked yes)
			(layer "F.SilkS")
			(effects
				(font
					(size 0.7874 0.5842)
					(thickness 0.1524)
				)
				(justify left)
			)
		)
		(property "Value" ""
			(at 0 0 270)
			(layer "F.Fab")
			(effects
				(font
					(size 1.27 1.27)
				)
			)
		)
		(duplicate_pad_numbers_are_jumpers no)
		(fp_line
			(start -2.249932 2.249932)
			(end -2.249932 1.3843)
			(stroke
				(width 0.1524)
				(type default)
			)
			(layer "F.SilkS")
		)
		(fp_line
			(start 2.249932 2.249932)
			(end -2.249932 2.249932)
			(stroke
				(width 0.1524)
				(type default)
			)
			(layer "F.SilkS")
		)
		(fp_line
			(start 2.249932 1.3843)
			(end 2.249932 2.249932)
			(stroke
				(width 0.1524)
				(type default)
			)
			(layer "F.SilkS")
		)
		(fp_line
			(start -2.249932 -1.3843)
			(end -2.249932 -2.249932)
			(stroke
				(width 0.1524)
				(type default)
			)
			(layer "F.SilkS")
		)
		(fp_line
			(start -2.249932 -2.249932)
			(end 2.249932 -2.249932)
			(stroke
				(width 0.1524)
				(type default)
			)
			(layer "F.SilkS")
		)
		(fp_line
			(start 2.249932 -2.249932)
			(end 2.249932 -1.3843)
			(stroke
				(width 0.1524)
				(type default)
			)
			(layer "F.SilkS")
		)
		(fp_line
			(start -2.249932 2.249932)
			(end -2.249932 -2.249932)
			(stroke
				(width 0.1)
				(type default)
			)
			(layer "F.Fab")
		)
		(fp_line
			(start 2.249932 2.249932)
			(end -2.249932 2.249932)
			(stroke
				(width 0.1)
				(type default)
			)
			(layer "F.Fab")
		)
		(fp_line
			(start -2.249932 -2.249932)
			(end 2.249932 -2.249932)
			(stroke
				(width 0.1)
				(type default)
			)
			(layer "F.Fab")
		)
		(fp_line
			(start 2.249932 -2.249932)
			(end 2.249932 2.249932)
			(stroke
				(width 0.1)
				(type default)
			)
			(layer "F.Fab")
		)
		(pad "1" smd rect
			(at -1.82499 0 270)
			(size 1.0668 2.5146)
			(layers "F.Cu" "F.Mask" "F.Paste")
			(net "SW_P12V_P0V8_PEX2_FLT")
		)
		(pad "2" smd rect
			(at 1.82499 0 270)
			(size 1.0668 2.5146)
			(layers "F.Cu" "F.Mask" "F.Paste")
			(net "P12V_AUX")
		)
	)
	(footprint ""
		(layer "F.Cu")
		(at 488.88269 -553.245274 180)
		(property "Reference" "JPEX1_FW1"
			(at -4.0259 -1.402334 0)
			(unlocked yes)
			(layer "B.SilkS")
			(effects
				(font
					(size 0.7874 0.5842)
					(thickness 0.1524)
				)
				(justify mirror)
			)
		)
		(property "Value" ""
			(at 0 0 180)
			(layer "F.Fab")
			(effects
				(font
					(size 1.27 1.27)
				)
			)
		)
		(duplicate_pad_numbers_are_jumpers no)
		(pad "1" thru_hole circle
			(at 0 0 180)
			(size 0.4572 0.4572)
			(drill 0.2032)
			(layers "*.Cu" "*.Mask")
			(remove_unused_layers no)
			(net "Net_9089")
			(clearance 0.127)
			(thermal_gap 0.127)
			(padstack
				(mode front_inner_back)
				(layer "Inner"
					(shape circle)
					(size 0.4572 0.4572)
					(clearance 0.127)
				)
				(layer "B.Cu"
					(shape circle)
					(size 0.508 0.508)
					(clearance 0.1016)
				)
			)
		)
	)
	(footprint ""
		(layer "F.Cu")
		(at 225.446844 -38.49116 180)
		(property "Reference" "R6088"
			(at 0 0 180)
			(layer "F.SilkS")
			(hide yes)
			(effects
				(font
					(size 1.27 1.27)
				)
			)
		)
		(property "Value" ""
			(at 0 0 180)
			(layer "F.Fab")
			(effects
				(font
					(size 1.27 1.27)
				)
			)
		)
		(duplicate_pad_numbers_are_jumpers no)
		(fp_line
			(start 0.7874 0.4064)
			(end -0.7874 0.4064)
			(stroke
				(width 0.1524)
				(type default)
			)
			(layer "F.SilkS")
		)
		(fp_line
			(start 0.7874 -0.4064)
			(end 0.7874 0.4064)
			(stroke
				(width 0.1524)
				(type default)
			)
			(layer "F.SilkS")
		)
		(fp_line
			(start -0.7874 0.4064)
			(end -0.7874 -0.4064)
			(stroke
				(width 0.1524)
				(type default)
			)
			(layer "F.SilkS")
		)
		(fp_line
			(start -0.7874 -0.4064)
			(end 0.7874 -0.4064)
			(stroke
				(width 0.1524)
				(type default)
			)
			(layer "F.SilkS")
		)
		(fp_line
			(start 0.67945 0.3048)
			(end 0.120396 0.3048)
			(stroke
				(width 0.1)
				(type default)
			)
			(layer "F.Fab")
		)
		(fp_line
			(start 0.67945 -0.3048)
			(end 0.67945 0.3048)
			(stroke
				(width 0.1)
				(type default)
			)
			(layer "F.Fab")
		)
		(fp_line
			(start 0.12065 -0.2794)
			(end 0.12065 -0.3048)
			(stroke
				(width 0.1)
				(type default)
			)
			(layer "F.Fab")
		)
		(fp_line
			(start 0.12065 -0.3048)
			(end 0.67945 -0.3048)
			(stroke
				(width 0.1)
				(type default)
			)
			(layer "F.Fab")
		)
		(fp_line
			(start 0.120396 0.3048)
			(end 0.120396 0.2794)
			(stroke
				(width 0.1)
				(type default)
			)
			(layer "F.Fab")
		)
		(fp_line
			(start 0.120396 0.2794)
			(end -0.12065 0.2794)
			(stroke
				(width 0.1)
				(type default)
			)
			(layer "F.Fab")
		)
		(fp_line
			(start -0.12065 0.3048)
			(end -0.67945 0.3048)
			(stroke
				(width 0.1)
				(type default)
			)
			(layer "F.Fab")
		)
		(fp_line
			(start -0.12065 0.2794)
			(end -0.12065 0.3048)
			(stroke
				(width 0.1)
				(type default)
			)
			(layer "F.Fab")
		)
		(fp_line
			(start -0.12065 -0.2794)
			(end 0.12065 -0.2794)
			(stroke
				(width 0.1)
				(type default)
			)
			(layer "F.Fab")
		)
		(fp_line
			(start -0.12065 -0.305054)
			(end -0.12065 -0.2794)
			(stroke
				(width 0.1)
				(type default)
			)
			(layer "F.Fab")
		)
		(fp_line
			(start -0.67945 0.3048)
			(end -0.67945 -0.305054)
			(stroke
				(width 0.1)
				(type default)
			)
			(layer "F.Fab")
		)
		(fp_line
			(start -0.67945 -0.305054)
			(end -0.12065 -0.305054)
			(stroke
				(width 0.1)
				(type default)
			)
			(layer "F.Fab")
		)
		(pad "1" smd circle
			(at -0.40005 0 180)
			(size 0 0)
			(layers "F.Cu" "F.Mask" "F.Paste")
			(net "P3V3_SSD8_PG_G1")
		)
		(pad "2" smd circle
			(at 0.40005 0 180)
			(size 0 0)
			(layers "F.Cu" "F.Mask" "F.Paste")
			(net "GND")
		)
	)
)
